(kicad_pcb
	(version 20241229)
	(generator "pcbnew")
	(generator_version "9.0")
	(general
		(thickness 1.61)
		(legacy_teardrops no)
	)
	(paper "A3")
	(title_block
		(title "RDIMM DDR5 Tester")
		(date "2026-05-21")
		(rev "2.2.0")
		(company "Antmicro")
		(comment 9 "footprints 474-478 of 796")
	)
	(layers
		(0 "F.Cu" signal)
		(4 "In1.Cu" power)
		(6 "In2.Cu" mixed)
		(8 "In3.Cu" power)
		(10 "In4.Cu" mixed)
		(12 "In5.Cu" power)
		(14 "In6.Cu" mixed)
		(16 "In7.Cu" power)
		(18 "In8.Cu" power)
		(20 "In9.Cu" mixed)
		(22 "In10.Cu" power)
		(2 "B.Cu" signal)
		(9 "F.Adhes" user "F.Adhesive")
		(11 "B.Adhes" user "B.Adhesive")
		(13 "F.Paste" user)
		(15 "B.Paste" user)
		(5 "F.SilkS" user "F.Silkscreen")
		(7 "B.SilkS" user "B.Silkscreen")
		(1 "F.Mask" user)
		(3 "B.Mask" user)
		(17 "Dwgs.User" user "User.Drawings")
		(19 "Cmts.User" user "User.Comments")
		(21 "Eco1.User" user "User.Eco1")
		(23 "Eco2.User" user "User.Eco2")
		(25 "Edge.Cuts" user)
		(27 "Margin" user)
		(31 "F.CrtYd" user "F.Courtyard")
		(29 "B.CrtYd" user "B.Courtyard")
		(35 "F.Fab" user)
		(33 "B.Fab" user)
	)
	(footprint "antmicro-footprints:C_0805_2012Metric"
		(layer "B.Cu")
		(at 219.334999 185.799999)
		(descr "Capacitor SMD 0805")
		(tags "capacitor SMD 0805")
		(property "Reference" "C201"
			(at 2.115001 0.800001 0)
			(layer "B.SilkS")
			(effects
				(font
					(size 0.7 0.7)
					(thickness 0.15)
				)
				(justify right bottom mirror)
			)
		)
		(property "Value" "C_22u_25V_0805"
			(at -2.055717 -1.963152 0)
			(layer "B.Fab")
			(effects
				(font
					(size 0.7 0.7)
					(thickness 0.15)
				)
				(justify right bottom mirror)
			)
		)
		(property "Datasheet" "https://product.samsungsem.com/mlcc/CL21A226MAYNNN.do"
			(at 0 0 0)
			(layer "F.Fab")
			(hide yes)
			(effects
				(font
					(size 1.27 1.27)
					(thickness 0.15)
				)
			)
		)
		(property "MPN" "CL21A226MAYNNNE"
			(at 0 0 0)
			(unlocked yes)
			(layer "B.Fab")
			(hide yes)
			(effects
				(font
					(size 1 1)
					(thickness 0.15)
				)
				(justify mirror)
			)
		)
		(property "Manufacturer" "Samsung Electro-Mechanics"
			(at 0 0 0)
			(unlocked yes)
			(layer "B.Fab")
			(hide yes)
			(effects
				(font
					(size 1 1)
					(thickness 0.15)
				)
				(justify mirror)
			)
		)
		(property "License" "Apache-2.0"
			(at 0 0 0)
			(unlocked yes)
			(layer "B.Fab")
			(hide yes)
			(effects
				(font
					(size 1 1)
					(thickness 0.15)
				)
				(justify mirror)
			)
		)
		(property "Author" "Antmicro"
			(at 0 0 0)
			(unlocked yes)
			(layer "B.Fab")
			(hide yes)
			(effects
				(font
					(size 1 1)
					(thickness 0.15)
				)
				(justify mirror)
			)
		)
		(property "Val" "22u"
			(at 0 0 0)
			(unlocked yes)
			(layer "B.Fab")
			(hide yes)
			(effects
				(font
					(size 1 1)
					(thickness 0.15)
				)
				(justify mirror)
			)
		)
		(property "Voltage" "25V"
			(at 0 0 0)
			(unlocked yes)
			(layer "B.Fab")
			(hide yes)
			(effects
				(font
					(size 1 1)
					(thickness 0.15)
				)
				(justify mirror)
			)
		)
		(property "Dielectric" "X5R"
			(at 0 0 0)
			(unlocked yes)
			(layer "B.Fab")
			(hide yes)
			(effects
				(font
					(size 1 1)
					(thickness 0.15)
				)
				(justify mirror)
			)
		)
		(property "Public" "False"
			(at 0 0 0)
			(unlocked yes)
			(layer "B.Fab")
			(hide yes)
			(effects
				(font
					(size 1 1)
					(thickness 0.15)
				)
				(justify mirror)
			)
		)
		(sheetname "/Supply/DC-DC VCCINT/")
		(sheetfile "dc-dc-vccint.kicad_sch")
		(attr smd)
		(fp_line
			(start -0.3 -0.7)
			(end 0.3 -0.7)
			(stroke
				(width 0.15)
				(type solid)
			)
			(layer "B.SilkS")
		)
		(fp_line
			(start -0.3 0.7)
			(end 0.3 0.7)
			(stroke
				(width 0.15)
				(type solid)
			)
			(layer "B.SilkS")
		)
		(fp_rect
			(start 1.95 0.9)
			(end -1.95 -0.9)
			(stroke
				(width 0.05)
				(type default)
			)
			(fill no)
			(layer "B.CrtYd")
		)
		(fp_rect
			(start -0.95 0.675)
			(end 0.95 -0.675)
			(stroke
				(width 0.15)
				(type solid)
			)
			(fill no)
			(layer "B.Fab")
		)
		(fp_text user "Author: Antmicro"
			(at -1.9 -5.947 180)
			(layer "B.Fab")
			(effects
				(font
					(size 0.7 0.7)
					(thickness 0.15)
				)
				(justify left bottom mirror)
			)
		)
		(fp_text user "${REFERENCE}"
			(at -1.9 -3.947 180)
			(layer "B.Fab")
			(effects
				(font
					(size 0.7 0.7)
					(thickness 0.15)
				)
				(justify left bottom mirror)
			)
		)
		(fp_text user "License: Apache-2.0"
			(at -1.9 -4.947 180)
			(layer "B.Fab")
			(effects
				(font
					(size 0.7 0.7)
					(thickness 0.15)
				)
				(justify left bottom mirror)
			)
		)
		(pad "1" smd roundrect
			(at -1.1 0)
			(size 1.2 1.3)
			(layers "B.Cu" "B.Mask" "B.Paste")
			(roundrect_rratio 0.25)
			(net 1 "GND")
			(pintype "passive")
		)
		(pad "2" smd roundrect
			(at 1.1 0)
			(size 1.2 1.3)
			(layers "B.Cu" "B.Mask" "B.Paste")
			(roundrect_rratio 0.25)
			(net 35 "VDC")
			(pintype "passive")
		)
	)
	(footprint "antmicro-footprints:R_0402_1005Metric"
		(layer "B.Cu")
		(at 240.12 176.975)
		(descr "Resistor SMD 0402")
		(tags "resistor SMD 0402")
		(property "Reference" "R208"
			(at 1.655 0.4 0)
			(layer "B.SilkS")
			(effects
				(font
					(size 0.7 0.7)
					(thickness 0.15)
				)
				(justify right bottom mirror)
			)
		)
		(property "Value" "R_0R_0402"
			(at -1.011843 -1.772047 0)
			(layer "B.Fab")
			(effects
				(font
					(size 0.7 0.7)
					(thickness 0.15)
				)
				(justify right bottom mirror)
			)
		)
		(property "Datasheet" "https://industrial.panasonic.com/cdbs/www-data/pdf/RDA0000/AOA0000C301.pdf"
			(at 0 0 0)
			(layer "F.Fab")
			(hide yes)
			(effects
				(font
					(size 1.27 1.27)
					(thickness 0.15)
				)
			)
		)
		(property "MPN" "ERJ2GE0R00X"
			(at 0 0 0)
			(unlocked yes)
			(layer "B.Fab")
			(hide yes)
			(effects
				(font
					(size 1 1)
					(thickness 0.15)
				)
				(justify mirror)
			)
		)
		(property "Manufacturer" "Panasonic"
			(at 0 0 0)
			(unlocked yes)
			(layer "B.Fab")
			(hide yes)
			(effects
				(font
					(size 1 1)
					(thickness 0.15)
				)
				(justify mirror)
			)
		)
		(property "License" "Apache-2.0"
			(at 0 0 0)
			(unlocked yes)
			(layer "B.Fab")
			(hide yes)
			(effects
				(font
					(size 1 1)
					(thickness 0.15)
				)
				(justify mirror)
			)
		)
		(property "Author" "Antmicro"
			(at 0 0 0)
			(unlocked yes)
			(layer "B.Fab")
			(hide yes)
			(effects
				(font
					(size 1 1)
					(thickness 0.15)
				)
				(justify mirror)
			)
		)
		(property "Val" "0R"
			(at 0 0 0)
			(unlocked yes)
			(layer "B.Fab")
			(hide yes)
			(effects
				(font
					(size 1 1)
					(thickness 0.15)
				)
				(justify mirror)
			)
		)
		(property "Tolerance" "~"
			(at 0 0 0)
			(unlocked yes)
			(layer "B.Fab")
			(hide yes)
			(effects
				(font
					(size 1 1)
					(thickness 0.15)
				)
				(justify mirror)
			)
		)
		(property "Current" "1A"
			(at 0 0 0)
			(unlocked yes)
			(layer "B.Fab")
			(hide yes)
			(effects
				(font
					(size 1 1)
					(thickness 0.15)
				)
				(justify mirror)
			)
		)
		(sheetname "/Supply/DC-DC AUX, MGT/")
		(sheetfile "dc-dc-aux-mgt.kicad_sch")
		(attr smd exclude_from_bom dnp)
		(fp_rect
			(start -0.925 0.47)
			(end 0.925 -0.47)
			(stroke
				(width 0.05)
				(type default)
			)
			(fill no)
			(layer "B.CrtYd")
		)
		(fp_rect
			(start -0.5 0.25)
			(end 0.5 -0.25)
			(stroke
				(width 0.15)
				(type solid)
			)
			(fill no)
			(layer "B.Fab")
		)
		(fp_text user "Author: Antmicro"
			(at -0.95 -4.169 180)
			(layer "B.Fab")
			(effects
				(font
					(size 0.7 0.7)
					(thickness 0.15)
				)
				(justify left bottom mirror)
			)
		)
		(fp_text user "${REFERENCE}"
			(at -0.95 -3.168 180)
			(layer "B.Fab")
			(effects
				(font
					(size 0.7 0.7)
					(thickness 0.15)
				)
				(justify left bottom mirror)
			)
		)
		(fp_text user "License: Apache-2.0"
			(at -0.95 -5.169 180)
			(layer "B.Fab")
			(effects
				(font
					(size 0.7 0.7)
					(thickness 0.15)
				)
				(justify left bottom mirror)
			)
		)
		(pad "1" smd roundrect
			(at -0.48 0)
			(size 0.59 0.64)
			(layers "B.Cu" "B.Mask" "B.Paste")
			(roundrect_rratio 0.25)
			(net 1 "GND")
			(pintype "passive")
		)
		(pad "2" smd roundrect
			(at 0.48 0)
			(size 0.59 0.64)
			(layers "B.Cu" "B.Mask" "B.Paste")
			(roundrect_rratio 0.25)
			(net 729 "Net-(U3-ADDRSEL)")
			(pintype "passive")
		)
	)
	(footprint "antmicro-footprints:C_0402_1005Metric_EIA"
		(layer "B.Cu")
		(at 187 146.5 -90)
		(descr "Capacitor SMD 0402 (1005 Metric), square (rectangular) end terminal, IPC_7351 nominal, (Body size source: IPC-SM-782 page 76, https://www.pcb-3d.com/wordpress/wp-content/uploads/ipc-sm-782a_amendment_1_and_2.pdf)")
		(tags "capacitor 0402")
		(property "Reference" "C77"
			(at -12.025 30.625 90)
			(layer "B.SilkS")
			(effects
				(font
					(size 0.7 0.7)
					(thickness 0.15)
				)
				(justify left bottom mirror)
			)
		)
		(property "Value" "C_1u_25V_0402"
			(at 0 -1.169 90)
			(layer "B.Fab")
			(effects
				(font
					(size 0.7 0.7)
					(thickness 0.15)
				)
				(justify left bottom mirror)
			)
		)
		(property "Datasheet" "https://www.murata.com/products/productdetail?partno=GRM155R61E105KE11%23"
			(at 0 0 270)
			(layer "F.Fab")
			(hide yes)
			(effects
				(font
					(size 1.27 1.27)
					(thickness 0.15)
				)
			)
		)
		(property "MPN" "GRM155R61E105KE11J"
			(at 0 0 270)
			(unlocked yes)
			(layer "B.Fab")
			(hide yes)
			(effects
				(font
					(size 1 1)
					(thickness 0.15)
				)
				(justify mirror)
			)
		)
		(property "Manufacturer" "Murata"
			(at 0 0 270)
			(unlocked yes)
			(layer "B.Fab")
			(hide yes)
			(effects
				(font
					(size 1 1)
					(thickness 0.15)
				)
				(justify mirror)
			)
		)
		(property "License" "Apache-2.0"
			(at 0 0 270)
			(unlocked yes)
			(layer "B.Fab")
			(hide yes)
			(effects
				(font
					(size 1 1)
					(thickness 0.15)
				)
				(justify mirror)
			)
		)
		(property "Author" "Antmicro"
			(at 0 0 270)
			(unlocked yes)
			(layer "B.Fab")
			(hide yes)
			(effects
				(font
					(size 1 1)
					(thickness 0.15)
				)
				(justify mirror)
			)
		)
		(property "Val" "1u"
			(at 0 0 270)
			(unlocked yes)
			(layer "B.Fab")
			(hide yes)
			(effects
				(font
					(size 1 1)
					(thickness 0.15)
				)
				(justify mirror)
			)
		)
		(property "Voltage" "25V"
			(at 0 0 270)
			(unlocked yes)
			(layer "B.Fab")
			(hide yes)
			(effects
				(font
					(size 1 1)
					(thickness 0.15)
				)
				(justify mirror)
			)
		)
		(property "Dielectric" "X5R"
			(at 0 0 270)
			(unlocked yes)
			(layer "B.Fab")
			(hide yes)
			(effects
				(font
					(size 1 1)
					(thickness 0.15)
				)
				(justify mirror)
			)
		)
		(sheetname "/FPGA power/")
		(sheetfile "fpga-power.kicad_sch")
		(attr smd)
		(fp_rect
			(start -0.95 0.45)
			(end 0.95 -0.45)
			(stroke
				(width 0.05)
				(type default)
			)
			(fill no)
			(layer "B.CrtYd")
		)
		(fp_line
			(start -0.5 0.25)
			(end 0.498 0.25)
			(stroke
				(width 0.15)
				(type solid)
			)
			(layer "B.Fab")
		)
		(fp_line
			(start 0.498 0.25)
			(end 0.498 -0.248)
			(stroke
				(width 0.15)
				(type solid)
			)
			(layer "B.Fab")
		)
		(fp_line
			(start -0.5 -0.248)
			(end -0.5 0.25)
			(stroke
				(width 0.15)
				(type solid)
			)
			(layer "B.Fab")
		)
		(fp_line
			(start 0.498 -0.248)
			(end -0.5 -0.248)
			(stroke
				(width 0.15)
				(type solid)
			)
			(layer "B.Fab")
		)
		(fp_text user "License: Apache-2.0"
			(at -0.9656 -4.369 90)
			(layer "B.Fab")
			(effects
				(font
					(size 0.7 0.7)
					(thickness 0.15)
				)
				(justify left bottom mirror)
			)
		)
		(fp_text user "Author: Antmicro"
			(at -0.9656 -5.569 90)
			(layer "B.Fab")
			(effects
				(font
					(size 0.7 0.7)
					(thickness 0.15)
				)
				(justify left bottom mirror)
			)
		)
		(fp_text user "${REFERENCE}"
			(at -0.9656 -3.169 90)
			(layer "B.Fab")
			(effects
				(font
					(size 0.7 0.7)
					(thickness 0.15)
				)
				(justify left bottom mirror)
			)
		)
		(pad "1" smd roundrect
			(at -0.5 0 180)
			(size 0.6 0.6)
			(layers "B.Cu" "B.Mask" "B.Paste")
			(roundrect_rratio 0.25)
			(net 1 "GND")
			(pintype "passive")
		)
		(pad "2" smd roundrect
			(at 0.498 0 270)
			(size 0.6 0.6)
			(layers "B.Cu" "B.Mask" "B.Paste")
			(roundrect_rratio 0.25)
			(net 797 "+1V8")
			(pintype "passive")
		)
	)
	(footprint "antmicro-footprints:C_0402_1005Metric_EIA"
		(layer "B.Cu")
		(at 182 141.5 90)
		(descr "Capacitor SMD 0402 (1005 Metric), square (rectangular) end terminal, IPC_7351 nominal, (Body size source: IPC-SM-782 page 76, https://www.pcb-3d.com/wordpress/wp-content/uploads/ipc-sm-782a_amendment_1_and_2.pdf)")
		(tags "capacitor 0402")
		(property "Reference" "C24"
			(at -1.075 1.45 90)
			(layer "B.SilkS")
			(effects
				(font
					(size 0.7 0.7)
					(thickness 0.15)
				)
				(justify right bottom mirror)
			)
		)
		(property "Value" "C_100n_0402"
			(at 0 -1.169 90)
			(layer "B.Fab")
			(effects
				(font
					(size 0.7 0.7)
					(thickness 0.15)
				)
				(justify right bottom mirror)
			)
		)
		(property "Datasheet" "https://www.murata.com/products/productdetail?partno=GRM155R61H104KE14%23"
			(at 0 0 90)
			(layer "F.Fab")
			(hide yes)
			(effects
				(font
					(size 1.27 1.27)
					(thickness 0.15)
				)
			)
		)
		(property "MPN" "GRM155R61H104KE14D"
			(at 0 0 90)
			(unlocked yes)
			(layer "B.Fab")
			(hide yes)
			(effects
				(font
					(size 1 1)
					(thickness 0.15)
				)
				(justify mirror)
			)
		)
		(property "Manufacturer" "Murata"
			(at 0 0 90)
			(unlocked yes)
			(layer "B.Fab")
			(hide yes)
			(effects
				(font
					(size 1 1)
					(thickness 0.15)
				)
				(justify mirror)
			)
		)
		(property "License" "Apache-2.0"
			(at 0 0 90)
			(unlocked yes)
			(layer "B.Fab")
			(hide yes)
			(effects
				(font
					(size 1 1)
					(thickness 0.15)
				)
				(justify mirror)
			)
		)
		(property "Author" "Antmicro"
			(at 0 0 90)
			(unlocked yes)
			(layer "B.Fab")
			(hide yes)
			(effects
				(font
					(size 1 1)
					(thickness 0.15)
				)
				(justify mirror)
			)
		)
		(property "Val" "100n"
			(at 0 0 90)
			(unlocked yes)
			(layer "B.Fab")
			(hide yes)
			(effects
				(font
					(size 1 1)
					(thickness 0.15)
				)
				(justify mirror)
			)
		)
		(property "Voltage" "50V"
			(at 0 0 90)
			(unlocked yes)
			(layer "B.Fab")
			(hide yes)
			(effects
				(font
					(size 1 1)
					(thickness 0.15)
				)
				(justify mirror)
			)
		)
		(property "Dielectric" "X5R"
			(at 0 0 90)
			(unlocked yes)
			(layer "B.Fab")
			(hide yes)
			(effects
				(font
					(size 1 1)
					(thickness 0.15)
				)
				(justify mirror)
			)
		)
		(sheetname "/FPGA power/")
		(sheetfile "fpga-power.kicad_sch")
		(attr smd)
		(fp_rect
			(start -0.95 0.45)
			(end 0.95 -0.45)
			(stroke
				(width 0.05)
				(type default)
			)
			(fill no)
			(layer "B.CrtYd")
		)
		(fp_line
			(start 0.498 -0.248)
			(end -0.5 -0.248)
			(stroke
				(width 0.15)
				(type solid)
			)
			(layer "B.Fab")
		)
		(fp_line
			(start -0.5 -0.248)
			(end -0.5 0.25)
			(stroke
				(width 0.15)
				(type solid)
			)
			(layer "B.Fab")
		)
		(fp_line
			(start 0.498 0.25)
			(end 0.498 -0.248)
			(stroke
				(width 0.15)
				(type solid)
			)
			(layer "B.Fab")
		)
		(fp_line
			(start -0.5 0.25)
			(end 0.498 0.25)
			(stroke
				(width 0.15)
				(type solid)
			)
			(layer "B.Fab")
		)
		(fp_text user "License: Apache-2.0"
			(at -0.9656 -4.369 270)
			(layer "B.Fab")
			(effects
				(font
					(size 0.7 0.7)
					(thickness 0.15)
				)
				(justify left bottom mirror)
			)
		)
		(fp_text user "${REFERENCE}"
			(at -0.9656 -3.169 270)
			(layer "B.Fab")
			(effects
				(font
					(size 0.7 0.7)
					(thickness 0.15)
				)
				(justify left bottom mirror)
			)
		)
		(fp_text user "Author: Antmicro"
			(at -0.9656 -5.569 270)
			(layer "B.Fab")
			(effects
				(font
					(size 0.7 0.7)
					(thickness 0.15)
				)
				(justify left bottom mirror)
			)
		)
		(pad "1" smd roundrect
			(at -0.5 0)
			(size 0.6 0.6)
			(layers "B.Cu" "B.Mask" "B.Paste")
			(roundrect_rratio 0.25)
			(net 1 "GND")
			(pintype "passive")
		)
		(pad "2" smd roundrect
			(at 0.498 0 90)
			(size 0.6 0.6)
			(layers "B.Cu" "B.Mask" "B.Paste")
			(roundrect_rratio 0.25)
			(net 687 "VDDQ")
			(pintype "passive")
		)
	)
	(footprint "antmicro-footprints:C_0402_1005Metric_EIA"
		(layer "B.Cu")
		(at 195 162.500001 90)
		(descr "Capacitor SMD 0402 (1005 Metric), square (rectangular) end terminal, IPC_7351 nominal, (Body size source: IPC-SM-782 page 76, https://www.pcb-3d.com/wordpress/wp-content/uploads/ipc-sm-782a_amendment_1_and_2.pdf)")
		(tags "capacitor 0402")
		(property "Reference" "C105"
			(at -3.949999 0.25 90)
			(layer "B.SilkS")
			(effects
				(font
					(size 0.7 0.7)
					(thickness 0.15)
				)
				(justify right bottom mirror)
			)
		)
		(property "Value" "C_100n_0402"
			(at 0 -1.169 90)
			(layer "B.Fab")
			(effects
				(font
					(size 0.7 0.7)
					(thickness 0.15)
				)
				(justify right bottom mirror)
			)
		)
		(property "Datasheet" "https://www.murata.com/products/productdetail?partno=GRM155R61H104KE14%23"
			(at 0 0 90)
			(layer "F.Fab")
			(hide yes)
			(effects
				(font
					(size 1.27 1.27)
					(thickness 0.15)
				)
			)
		)
		(property "MPN" "GRM155R61H104KE14D"
			(at 0 0 90)
			(unlocked yes)
			(layer "B.Fab")
			(hide yes)
			(effects
				(font
					(size 1 1)
					(thickness 0.15)
				)
				(justify mirror)
			)
		)
		(property "Manufacturer" "Murata"
			(at 0 0 90)
			(unlocked yes)
			(layer "B.Fab")
			(hide yes)
			(effects
				(font
					(size 1 1)
					(thickness 0.15)
				)
				(justify mirror)
			)
		)
		(property "License" "Apache-2.0"
			(at 0 0 90)
			(unlocked yes)
			(layer "B.Fab")
			(hide yes)
			(effects
				(font
					(size 1 1)
					(thickness 0.15)
				)
				(justify mirror)
			)
		)
		(property "Author" "Antmicro"
			(at 0 0 90)
			(unlocked yes)
			(layer "B.Fab")
			(hide yes)
			(effects
				(font
					(size 1 1)
					(thickness 0.15)
				)
				(justify mirror)
			)
		)
		(property "Val" "100n"
			(at 0 0 90)
			(unlocked yes)
			(layer "B.Fab")
			(hide yes)
			(effects
				(font
					(size 1 1)
					(thickness 0.15)
				)
				(justify mirror)
			)
		)
		(property "Voltage" "50V"
			(at 0 0 90)
			(unlocked yes)
			(layer "B.Fab")
			(hide yes)
			(effects
				(font
					(size 1 1)
					(thickness 0.15)
				)
				(justify mirror)
			)
		)
		(property "Dielectric" "X5R"
			(at 0 0 90)
			(unlocked yes)
			(layer "B.Fab")
			(hide yes)
			(effects
				(font
					(size 1 1)
					(thickness 0.15)
				)
				(justify mirror)
			)
		)
		(sheetname "/FPGA power/")
		(sheetfile "fpga-power.kicad_sch")
		(attr smd)
		(fp_rect
			(start -0.95 0.45)
			(end 0.95 -0.45)
			(stroke
				(width 0.05)
				(type default)
			)
			(fill no)
			(layer "B.CrtYd")
		)
		(fp_line
			(start 0.498 -0.248)
			(end -0.5 -0.248)
			(stroke
				(width 0.15)
				(type solid)
			)
			(layer "B.Fab")
		)
		(fp_line
			(start -0.5 -0.248)
			(end -0.5 0.25)
			(stroke
				(width 0.15)
				(type solid)
			)
			(layer "B.Fab")
		)
		(fp_line
			(start 0.498 0.25)
			(end 0.498 -0.248)
			(stroke
				(width 0.15)
				(type solid)
			)
			(layer "B.Fab")
		)
		(fp_line
			(start -0.5 0.25)
			(end 0.498 0.25)
			(stroke
				(width 0.15)
				(type solid)
			)
			(layer "B.Fab")
		)
		(fp_text user "License: Apache-2.0"
			(at -0.9656 -4.369 270)
			(layer "B.Fab")
			(effects
				(font
					(size 0.7 0.7)
					(thickness 0.15)
				)
				(justify left bottom mirror)
			)
		)
		(fp_text user "Author: Antmicro"
			(at -0.9656 -5.569 270)
			(layer "B.Fab")
			(effects
				(font
					(size 0.7 0.7)
					(thickness 0.15)
				)
				(justify left bottom mirror)
			)
		)
		(fp_text user "${REFERENCE}"
			(at -0.9656 -3.169 270)
			(layer "B.Fab")
			(effects
				(font
					(size 0.7 0.7)
					(thickness 0.15)
				)
				(justify left bottom mirror)
			)
		)
		(pad "1" smd roundrect
			(at -0.5 0)
			(size 0.6 0.6)
			(layers "B.Cu" "B.Mask" "B.Paste")
			(roundrect_rratio 0.25)
			(net 1 "GND")
			(pintype "passive")
		)
		(pad "2" smd roundrect
			(at 0.498 0 90)
			(size 0.6 0.6)
			(layers "B.Cu" "B.Mask" "B.Paste")
			(roundrect_rratio 0.25)
			(net 172 "+1V2_MGTAVTT")
			(pintype "passive")
		)
	)
)
